# S9S_MB_2U (Grand Teton) — schematic netlist excerpt (pin names and nets, part order shuffled) for the footprints in the layout excerpt that follows; sources: Cadence DE-HDL packaged netlist, KiCad conversion of 03242023_DA0F0TMBIJ0_F0T_Motherboard_J_brd_V01_OCP.brd

PC1244_P1_3  Q_CAP  2.2UF 10V 10% X6S  pkg C0402  page 290 : A = PVCCFA_EHV_FIVRA_CPU1_PVCC1 ; B = GND
R2837  Q_RES  100K 1% EMPTY  pkg 0402LF  page 148 : A = P3V3_AUX ; B = FM_SWB_PWRGD

(kicad_pcb
	(version 20260206)
	(generator "pcbnew")
	(generator_version "10.0")
	(general
		(thickness 1.6)
		(legacy_teardrops no)
	)
	(paper "A4")
	(title_block
		(title "03242023_DA0F0TMBIJ0_F0T_Motherboard_J_brd_V01_OCP.brd")
		(comment 1 "Grand Teton / footprints 2742-2743 of 6105")
	)
	(layers
		(0 "F.Cu" signal "TOP")
		(4 "In1.Cu" signal "GND")
		(6 "In2.Cu" signal "IN1")
		(8 "In3.Cu" signal "GND1")
		(10 "In4.Cu" signal "IN2")
		(12 "In5.Cu" signal "GND2")
		(14 "In6.Cu" signal "IN3")
		(16 "In7.Cu" signal "GND3")
		(18 "In8.Cu" signal "VCC")
		(20 "In9.Cu" signal "VCC1")
		(22 "In10.Cu" signal "GND4")
		(24 "In11.Cu" signal "IN4")
		(26 "In12.Cu" signal "GND5")
		(28 "In13.Cu" signal "IN5")
		(30 "In14.Cu" signal "GND6")
		(32 "In15.Cu" signal "IN6")
		(34 "In16.Cu" signal "GND7")
		(2 "B.Cu" signal "BOTTOM")
		(9 "F.Adhes" user "F.Adhesive")
		(11 "B.Adhes" user "B.Adhesive")
		(13 "F.Paste" user "Package Geometry/Pastemask Top")
		(15 "B.Paste" user "Package Geometry/Pastemask Bottom")
		(5 "F.SilkS" user "Ref Des/Silkscreen Top")
		(7 "B.SilkS" user "Ref Des/Silkscreen Bottom")
		(1 "F.Mask" user "Board Geometry/Soldermask Top")
		(3 "B.Mask" user "Board Geometry/Soldermask Bottom")
		(17 "Dwgs.User" user "User.Drawings")
		(19 "Cmts.User" user "User.Comments")
		(21 "Eco1.User" user "User.Eco1")
		(23 "Eco2.User" user "User.Eco2")
		(25 "Edge.Cuts" user "Board Geometry/Outline")
		(27 "Margin" user)
		(31 "F.CrtYd" user "Package Geometry/Place Bound Top")
		(29 "B.CrtYd" user "Package Geometry/Place Bound Bottom")
		(35 "F.Fab" user "Ref Des/Assembly Top")
		(33 "B.Fab" user "Ref Des/Assembly Bottom")
	)
	(footprint ""
		(layer "F.Cu")
		(at 424.204892 -386.298948)
		(property "Reference" "R2837"
			(at 0 0 0)
			(layer "F.SilkS")
			(hide yes)
			(effects
				(font
					(size 1.27 1.27)
				)
			)
		)
		(property "Value" ""
			(at 0 0 0)
			(layer "F.Fab")
			(effects
				(font
					(size 1.27 1.27)
				)
			)
		)
		(duplicate_pad_numbers_are_jumpers no)
		(fp_line
			(start -0.7874 -0.4064)
			(end 0.7874 -0.4064)
			(stroke
				(width 0.1524)
				(type default)
			)
			(layer "F.SilkS")
		)
		(fp_line
			(start -0.7874 0.4064)
			(end -0.7874 -0.4064)
			(stroke
				(width 0.1524)
				(type default)
			)
			(layer "F.SilkS")
		)
		(fp_line
			(start 0.7874 -0.4064)
			(end 0.7874 0.4064)
			(stroke
				(width 0.1524)
				(type default)
			)
			(layer "F.SilkS")
		)
		(fp_line
			(start 0.7874 0.4064)
			(end -0.7874 0.4064)
			(stroke
				(width 0.1524)
				(type default)
			)
			(layer "F.SilkS")
		)
		(fp_line
			(start -0.67945 -0.305054)
			(end -0.12065 -0.305054)
			(stroke
				(width 0.1)
				(type default)
			)
			(layer "F.Fab")
		)
		(fp_line
			(start -0.67945 0.3048)
			(end -0.67945 -0.305054)
			(stroke
				(width 0.1)
				(type default)
			)
			(layer "F.Fab")
		)
		(fp_line
			(start -0.12065 -0.305054)
			(end -0.12065 -0.2794)
			(stroke
				(width 0.1)
				(type default)
			)
			(layer "F.Fab")
		)
		(fp_line
			(start -0.12065 -0.2794)
			(end 0.12065 -0.2794)
			(stroke
				(width 0.1)
				(type default)
			)
			(layer "F.Fab")
		)
		(fp_line
			(start -0.12065 0.2794)
			(end -0.12065 0.3048)
			(stroke
				(width 0.1)
				(type default)
			)
			(layer "F.Fab")
		)
		(fp_line
			(start -0.12065 0.3048)
			(end -0.67945 0.3048)
			(stroke
				(width 0.1)
				(type default)
			)
			(layer "F.Fab")
		)
		(fp_line
			(start 0.120396 0.2794)
			(end -0.12065 0.2794)
			(stroke
				(width 0.1)
				(type default)
			)
			(layer "F.Fab")
		)
		(fp_line
			(start 0.120396 0.3048)
			(end 0.120396 0.2794)
			(stroke
				(width 0.1)
				(type default)
			)
			(layer "F.Fab")
		)
		(fp_line
			(start 0.12065 -0.3048)
			(end 0.67945 -0.3048)
			(stroke
				(width 0.1)
				(type default)
			)
			(layer "F.Fab")
		)
		(fp_line
			(start 0.12065 -0.2794)
			(end 0.12065 -0.3048)
			(stroke
				(width 0.1)
				(type default)
			)
			(layer "F.Fab")
		)
		(fp_line
			(start 0.67945 -0.3048)
			(end 0.67945 0.3048)
			(stroke
				(width 0.1)
				(type default)
			)
			(layer "F.Fab")
		)
		(fp_line
			(start 0.67945 0.3048)
			(end 0.120396 0.3048)
			(stroke
				(width 0.1)
				(type default)
			)
			(layer "F.Fab")
		)
		(pad "1" smd circle
			(at -0.40005 0)
			(size 0 0)
			(layers "F.Cu" "F.Mask" "F.Paste")
			(net "P3V3_AUX")
		)
		(pad "2" smd circle
			(at 0.40005 0)
			(size 0 0)
			(layers "F.Cu" "F.Mask" "F.Paste")
			(net "FM_SWB_PWRGD")
		)
	)
	(footprint ""
		(layer "F.Cu")
		(at 178.13782 -353.36353 -90)
		(property "Reference" "PC1244_P1_3"
			(at 0 0 270)
			(layer "F.SilkS")
			(hide yes)
			(effects
				(font
					(size 1.27 1.27)
				)
			)
		)
		(property "Value" ""
			(at 0 0 270)
			(layer "F.Fab")
			(effects
				(font
					(size 1.27 1.27)
				)
			)
		)
		(duplicate_pad_numbers_are_jumpers no)
		(fp_line
			(start -0.7874 0.4064)
			(end -0.7874 -0.4064)
			(stroke
				(width 0.1524)
				(type default)
			)
			(layer "F.SilkS")
		)
		(fp_line
			(start 0.7874 0.4064)
			(end -0.7874 0.4064)
			(stroke
				(width 0.1524)
				(type default)
			)
			(layer "F.SilkS")
		)
		(fp_line
			(start -0.7874 -0.4064)
			(end 0.7874 -0.4064)
			(stroke
				(width 0.1524)
				(type default)
			)
			(layer "F.SilkS")
		)
		(fp_line
			(start 0.7874 -0.4064)
			(end 0.7874 0.4064)
			(stroke
				(width 0.1524)
				(type default)
			)
			(layer "F.SilkS")
		)
		(fp_line
			(start -0.67945 0.3048)
			(end -0.67945 -0.305054)
			(stroke
				(width 0.1)
				(type default)
			)
			(layer "F.Fab")
		)
		(fp_line
			(start -0.12065 0.3048)
			(end -0.67945 0.3048)
			(stroke
				(width 0.1)
				(type default)
			)
			(layer "F.Fab")
		)
		(fp_line
			(start 0.120396 0.3048)
			(end 0.120396 0.2794)
			(stroke
				(width 0.1)
				(type default)
			)
			(layer "F.Fab")
		)
		(fp_line
			(start 0.67945 0.3048)
			(end 0.120396 0.3048)
			(stroke
				(width 0.1)
				(type default)
			)
			(layer "F.Fab")
		)
		(fp_line
			(start -0.12065 0.2794)
			(end -0.12065 0.3048)
			(stroke
				(width 0.1)
				(type default)
			)
			(layer "F.Fab")
		)
		(fp_line
			(start 0.120396 0.2794)
			(end -0.12065 0.2794)
			(stroke
				(width 0.1)
				(type default)
			)
			(layer "F.Fab")
		)
		(fp_line
			(start -0.12065 -0.2794)
			(end 0.12065 -0.2794)
			(stroke
				(width 0.1)
				(type default)
			)
			(layer "F.Fab")
		)
		(fp_line
			(start 0.12065 -0.2794)
			(end 0.12065 -0.3048)
			(stroke
				(width 0.1)
				(type default)
			)
			(layer "F.Fab")
		)
		(fp_line
			(start 0.12065 -0.3048)
			(end 0.67945 -0.3048)
			(stroke
				(width 0.1)
				(type default)
			)
			(layer "F.Fab")
		)
		(fp_line
			(start 0.67945 -0.3048)
			(end 0.67945 0.3048)
			(stroke
				(width 0.1)
				(type default)
			)
			(layer "F.Fab")
		)
		(fp_line
			(start -0.67945 -0.305054)
			(end -0.12065 -0.305054)
			(stroke
				(width 0.1)
				(type default)
			)
			(layer "F.Fab")
		)
		(fp_line
			(start -0.12065 -0.305054)
			(end -0.12065 -0.2794)
			(stroke
				(width 0.1)
				(type default)
			)
			(layer "F.Fab")
		)
		(pad "1" smd circle
			(at -0.40005 0 270)
			(size 0 0)
			(layers "F.Cu" "F.Mask" "F.Paste")
			(net "PVCCFA_EHV_FIVRA_CPU1_PVCC1")
		)
		(pad "2" smd circle
			(at 0.40005 0 270)
			(size 0 0)
			(layers "F.Cu" "F.Mask" "F.Paste")
			(net "GND")
		)
	)
)
